#ISCELL
  mstr_misc dns *
  *
#ISCELL
  pure_quanta quanta_title_block_c *
  *
#CELL
  pure_quanta nc7sb3157p6x *
  page130_i1
#ISCELL
  standard offpage *
  page130_i10
#CELL
  pure_quanta q_res *
  page130_i11
#CELL
  pure_quanta q_res *
  page130_i12
#ISCELL
  standard offpage *
  page130_i13
#ISCELL
  standard offpage *
  page130_i14
#ISCELL
  pure_quanta_power universal_power *
  page130_i16
#ISCELL
  pure_quanta_power universal_power *
  page130_i17
#ISCELL
  pure_quanta_power gnd *
  page130_i2
#ISCELL
  standard offpage *
  page130_i21
#ISCELL
  standard offpage *
  page130_i22
#CELL
  pure_quanta q_res *
  page130_i23
#CELL
  pure_quanta q_res *
  page130_i24
#ISCELL
  pure_quanta_power universal_power *
  page130_i3
#CELL
  pure_quanta q_cap *
  page130_i4
#ISCELL
  pure_quanta_power gnd *
  page130_i5
#ISCELL
  standard offpage *
  page130_i8
